# S9S_MB_2U (Grand Teton) — schematic netlist excerpt (pin names and nets, part order shuffled) for the footprints in the layout excerpt that follows; sources: Cadence DE-HDL packaged netlist, KiCad conversion of 03242023_DA0F0TMBIJ0_F0T_Motherboard_J_brd_V01_OCP.brd

PC570_P1_2  Q_CAP  22UF 16V 20% X6S  pkg C0805  page 285 : A = SW_P12V_PVCCIN_CPU1_FLT ; B = GND
C503  Q_CAP  47UF 4V 20% X6S  pkg C0805  page 76 : A = PVCCD_HV_CPU0 ; B = GND
C1388  Q_CAP  47UF 4V 20% X6S  pkg C0805  page 78 : A = PVPP_HBM_CPU1 ; B = GND
C502  Q_CAP  47UF 4V 20% X6S  pkg C0805  page 76 : A = PVCCFA_EHV_FIVRA_CPU0 ; B = GND

(kicad_pcb
	(version 20260206)
	(generator "pcbnew")
	(generator_version "10.0")
	(general
		(thickness 1.6)
		(legacy_teardrops no)
	)
	(paper "A4")
	(title_block
		(title "03242023_DA0F0TMBIJ0_F0T_Motherboard_J_brd_V01_OCP.brd")
		(comment 1 "Grand Teton / footprints 4906-4909 of 6105")
	)
	(layers
		(0 "F.Cu" signal "TOP")
		(4 "In1.Cu" signal "GND")
		(6 "In2.Cu" signal "IN1")
		(8 "In3.Cu" signal "GND1")
		(10 "In4.Cu" signal "IN2")
		(12 "In5.Cu" signal "GND2")
		(14 "In6.Cu" signal "IN3")
		(16 "In7.Cu" signal "GND3")
		(18 "In8.Cu" signal "VCC")
		(20 "In9.Cu" signal "VCC1")
		(22 "In10.Cu" signal "GND4")
		(24 "In11.Cu" signal "IN4")
		(26 "In12.Cu" signal "GND5")
		(28 "In13.Cu" signal "IN5")
		(30 "In14.Cu" signal "GND6")
		(32 "In15.Cu" signal "IN6")
		(34 "In16.Cu" signal "GND7")
		(2 "B.Cu" signal "BOTTOM")
		(9 "F.Adhes" user "F.Adhesive")
		(11 "B.Adhes" user "B.Adhesive")
		(13 "F.Paste" user "Package Geometry/Pastemask Top")
		(15 "B.Paste" user "Package Geometry/Pastemask Bottom")
		(5 "F.SilkS" user "Ref Des/Silkscreen Top")
		(7 "B.SilkS" user "Ref Des/Silkscreen Bottom")
		(1 "F.Mask" user "Board Geometry/Soldermask Top")
		(3 "B.Mask" user "Board Geometry/Soldermask Bottom")
		(17 "Dwgs.User" user "User.Drawings")
		(19 "Cmts.User" user "User.Comments")
		(21 "Eco1.User" user "User.Eco1")
		(23 "Eco2.User" user "User.Eco2")
		(25 "Edge.Cuts" user "Board Geometry/Outline")
		(27 "Margin" user)
		(31 "F.CrtYd" user "Package Geometry/Place Bound Top")
		(29 "B.CrtYd" user "Package Geometry/Place Bound Bottom")
		(35 "F.Fab" user "Ref Des/Assembly Top")
		(33 "B.Fab" user "Ref Des/Assembly Bottom")
	)
	(footprint ""
		(layer "B.Cu")
		(at 406.754838 -250.75515 90)
		(property "Reference" "C502"
			(at 0 0 90)
			(layer "B.SilkS")
			(hide yes)
			(effects
				(font
					(size 1.27 1.27)
				)
				(justify mirror)
			)
		)
		(property "Value" ""
			(at 0 0 90)
			(layer "B.Fab")
			(effects
				(font
					(size 1.27 1.27)
				)
				(justify mirror)
			)
		)
		(duplicate_pad_numbers_are_jumpers no)
		(fp_line
			(start 1.524 -0.762)
			(end -1.524 -0.762)
			(stroke
				(width 0.1524)
				(type default)
			)
			(layer "B.SilkS")
		)
		(fp_line
			(start -1.524 -0.762)
			(end -1.524 0.762)
			(stroke
				(width 0.1524)
				(type default)
			)
			(layer "B.SilkS")
		)
		(fp_line
			(start 1.524 0.762)
			(end 1.524 -0.762)
			(stroke
				(width 0.1524)
				(type default)
			)
			(layer "B.SilkS")
		)
		(fp_line
			(start -1.524 0.762)
			(end 1.524 0.762)
			(stroke
				(width 0.1524)
				(type default)
			)
			(layer "B.SilkS")
		)
		(fp_line
			(start 1.1049 -0.724916)
			(end 1.1049 0.724916)
			(stroke
				(width 0.1)
				(type default)
			)
			(layer "B.Fab")
		)
		(fp_line
			(start -1.1049 -0.724916)
			(end 1.1049 -0.724916)
			(stroke
				(width 0.1)
				(type default)
			)
			(layer "B.Fab")
		)
		(fp_line
			(start 1.1049 0.724916)
			(end -1.1049 0.724916)
			(stroke
				(width 0.1)
				(type default)
			)
			(layer "B.Fab")
		)
		(fp_line
			(start -1.1049 0.724916)
			(end -1.1049 -0.724916)
			(stroke
				(width 0.1)
				(type default)
			)
			(layer "B.Fab")
		)
		(pad "1" smd rect
			(at 0.889 0 90)
			(size 1.016 1.27)
			(layers "B.Cu" "B.Mask" "B.Paste")
			(net "PVCCFA_EHV_FIVRA_CPU0")
		)
		(pad "2" smd rect
			(at -0.889 0 90)
			(size 1.016 1.27)
			(layers "B.Cu" "B.Mask" "B.Paste")
			(net "GND")
		)
	)
	(footprint ""
		(layer "B.Cu")
		(at 362.6739 -212.049614 180)
		(property "Reference" "C503"
			(at 0 0 0)
			(layer "B.SilkS")
			(hide yes)
			(effects
				(font
					(size 1.27 1.27)
				)
				(justify mirror)
			)
		)
		(property "Value" ""
			(at 0 0 0)
			(layer "B.Fab")
			(effects
				(font
					(size 1.27 1.27)
				)
				(justify mirror)
			)
		)
		(duplicate_pad_numbers_are_jumpers no)
		(fp_line
			(start 1.524 0.762)
			(end 1.524 -0.762)
			(stroke
				(width 0.1524)
				(type default)
			)
			(layer "B.SilkS")
		)
		(fp_line
			(start 1.524 -0.762)
			(end -1.524 -0.762)
			(stroke
				(width 0.1524)
				(type default)
			)
			(layer "B.SilkS")
		)
		(fp_line
			(start -1.524 0.762)
			(end 1.524 0.762)
			(stroke
				(width 0.1524)
				(type default)
			)
			(layer "B.SilkS")
		)
		(fp_line
			(start -1.524 -0.762)
			(end -1.524 0.762)
			(stroke
				(width 0.1524)
				(type default)
			)
			(layer "B.SilkS")
		)
		(fp_line
			(start 1.1049 0.724916)
			(end -1.1049 0.724916)
			(stroke
				(width 0.1)
				(type default)
			)
			(layer "B.Fab")
		)
		(fp_line
			(start 1.1049 -0.724916)
			(end 1.1049 0.724916)
			(stroke
				(width 0.1)
				(type default)
			)
			(layer "B.Fab")
		)
		(fp_line
			(start -1.1049 0.724916)
			(end -1.1049 -0.724916)
			(stroke
				(width 0.1)
				(type default)
			)
			(layer "B.Fab")
		)
		(fp_line
			(start -1.1049 -0.724916)
			(end 1.1049 -0.724916)
			(stroke
				(width 0.1)
				(type default)
			)
			(layer "B.Fab")
		)
		(pad "1" smd rect
			(at 0.889 0 180)
			(size 1.016 1.27)
			(layers "B.Cu" "B.Mask" "B.Paste")
			(net "PVCCD_HV_CPU0")
		)
		(pad "2" smd rect
			(at -0.889 0 180)
			(size 1.016 1.27)
			(layers "B.Cu" "B.Mask" "B.Paste")
			(net "GND")
		)
	)
	(footprint ""
		(layer "B.Cu")
		(at 108.415074 -333.639922 90)
		(property "Reference" "PC570_P1_2"
			(at 0 0 90)
			(layer "B.SilkS")
			(hide yes)
			(effects
				(font
					(size 1.27 1.27)
				)
				(justify mirror)
			)
		)
		(property "Value" ""
			(at 0 0 90)
			(layer "B.Fab")
			(effects
				(font
					(size 1.27 1.27)
				)
				(justify mirror)
			)
		)
		(duplicate_pad_numbers_are_jumpers no)
		(fp_line
			(start 1.524 -0.762)
			(end -1.524 -0.762)
			(stroke
				(width 0.1524)
				(type default)
			)
			(layer "B.SilkS")
		)
		(fp_line
			(start -1.524 -0.762)
			(end -1.524 0.762)
			(stroke
				(width 0.1524)
				(type default)
			)
			(layer "B.SilkS")
		)
		(fp_line
			(start 1.524 0.762)
			(end 1.524 -0.762)
			(stroke
				(width 0.1524)
				(type default)
			)
			(layer "B.SilkS")
		)
		(fp_line
			(start -1.524 0.762)
			(end 1.524 0.762)
			(stroke
				(width 0.1524)
				(type default)
			)
			(layer "B.SilkS")
		)
		(fp_line
			(start 1.1049 -0.724916)
			(end 1.1049 0.724916)
			(stroke
				(width 0.1)
				(type default)
			)
			(layer "B.Fab")
		)
		(fp_line
			(start -1.1049 -0.724916)
			(end 1.1049 -0.724916)
			(stroke
				(width 0.1)
				(type default)
			)
			(layer "B.Fab")
		)
		(fp_line
			(start 1.1049 0.724916)
			(end -1.1049 0.724916)
			(stroke
				(width 0.1)
				(type default)
			)
			(layer "B.Fab")
		)
		(fp_line
			(start -1.1049 0.724916)
			(end -1.1049 -0.724916)
			(stroke
				(width 0.1)
				(type default)
			)
			(layer "B.Fab")
		)
		(pad "1" smd rect
			(at 0.889 0 90)
			(size 1.016 1.27)
			(layers "B.Cu" "B.Mask" "B.Paste")
			(net "SW_P12V_PVCCIN_CPU1_FLT")
		)
		(pad "2" smd rect
			(at -0.889 0 90)
			(size 1.016 1.27)
			(layers "B.Cu" "B.Mask" "B.Paste")
			(net "GND")
		)
	)
	(footprint ""
		(layer "B.Cu")
		(at 118.097554 -262.34898 180)
		(property "Reference" "C1388"
			(at 0 0 0)
			(layer "B.SilkS")
			(hide yes)
			(effects
				(font
					(size 1.27 1.27)
				)
				(justify mirror)
			)
		)
		(property "Value" ""
			(at 0 0 0)
			(layer "B.Fab")
			(effects
				(font
					(size 1.27 1.27)
				)
				(justify mirror)
			)
		)
		(duplicate_pad_numbers_are_jumpers no)
		(fp_line
			(start 1.524 0.762)
			(end 1.524 -0.762)
			(stroke
				(width 0.1524)
				(type default)
			)
			(layer "B.SilkS")
		)
		(fp_line
			(start 1.524 -0.762)
			(end -1.524 -0.762)
			(stroke
				(width 0.1524)
				(type default)
			)
			(layer "B.SilkS")
		)
		(fp_line
			(start -1.524 0.762)
			(end 1.524 0.762)
			(stroke
				(width 0.1524)
				(type default)
			)
			(layer "B.SilkS")
		)
		(fp_line
			(start -1.524 -0.762)
			(end -1.524 0.762)
			(stroke
				(width 0.1524)
				(type default)
			)
			(layer "B.SilkS")
		)
		(fp_line
			(start 1.1049 0.724916)
			(end -1.1049 0.724916)
			(stroke
				(width 0.1)
				(type default)
			)
			(layer "B.Fab")
		)
		(fp_line
			(start 1.1049 -0.724916)
			(end 1.1049 0.724916)
			(stroke
				(width 0.1)
				(type default)
			)
			(layer "B.Fab")
		)
		(fp_line
			(start -1.1049 0.724916)
			(end -1.1049 -0.724916)
			(stroke
				(width 0.1)
				(type default)
			)
			(layer "B.Fab")
		)
		(fp_line
			(start -1.1049 -0.724916)
			(end 1.1049 -0.724916)
			(stroke
				(width 0.1)
				(type default)
			)
			(layer "B.Fab")
		)
		(pad "1" smd rect
			(at 0.889 0 180)
			(size 1.016 1.27)
			(layers "B.Cu" "B.Mask" "B.Paste")
			(net "PVPP_HBM_CPU1")
		)
		(pad "2" smd rect
			(at -0.889 0 180)
			(size 1.016 1.27)
			(layers "B.Cu" "B.Mask" "B.Paste")
			(net "GND")
		)
	)
)
